FILE_TYPE = MACRO_DRAWING;
SET COLOR_WIRE YELLOW;
SET COLOR_PROP ORANGE;
SET COLOR_DOT WHITE;
SET COLOR_ARC YELLOW;
SET COLOR_BODY GREEN;
SET COLOR_NOTE PURPLE;
SET PROP_DISPLAY VALUE;
SET PAGE_NUMBER P468;
FORCEADD QUANTA_TITLE_BLOCK_C..1
(0 0);
FORCEPROP 1 LAST CUSTOM_TXT_CDS <NAME_2>
J 0
(-3175 50);
FORCEPROP 1 LAST CUSTOM_TXT_CDS <NAME_1>
J 0
(-3175 175);
FORCEPROP 1 LAST CUSTOM_TXT_CDS <Q_NUMBER>
J 0
(-1403 103);
DISPLAY 1.212766 (-1403 103);
FORCEPROP 1 LAST CUSTOM_TXT_CDS <Q_PROJ>
J 0
(-2382 102);
DISPLAY 1.212766 (-2382 102);
FORCEPROP 1 LAST CUSTOM_TXT_CDS <Q_REV>
J 0
(-184 103);
DISPLAY 1.212766 (-184 103);
FORCEPROP 1 LAST CUSTOM_TXT_CDS <CON_LAST_MODIFIED>
J 0
(-1885 15);
DISPLAY 0.978723 (-1885 15);
FORCEPROP 1 LAST CUSTOM_TXT_CDS <CON_PAGE_NUM> OF <CON_TOTAL_PAGES>
J 0
(-446 18);
DISPLAY 0.978723 (-446 18);
FORCEPROP 1 LAST Q_TITLE Blank
J 0
(-9366 26);
DISPLAY 2.446809 (-9366 26);
PAINT GREEN (-9366 26);
FORCEPROP 2 LAST CDS_LIB pure_quanta
J 0
(0 0);
DISPLAY INVISIBLE (0 0);
FORCEPROP 1 LAST CDS_LMAN_SYM_OUTLINE -9475,6775,100,-125
J 0
(0 0);
DISPLAY 0.468085 (0 0);
PAINT GREEN (0 0);
DISPLAY INVISIBLE (0 0);
FORCEPROP 2 LAST PAGE_BORDER TRUE
J 0
(-7890 5250);
DISPLAY 0.638298 (-7890 5250);
PAINT PINK (-7890 5250);
DISPLAY INVISIBLE (-7890 5250);
FORCEPROP 2 LAST CDS_XR_PAGE_TITLE CR-360 : @T6G_MB_LIB.T6G(SCH_1):PAGE360
J 0
(-7890 5250);
DISPLAY 0.638298 (-7890 5250);
PAINT PINK (-7890 5250);
DISPLAY INVISIBLE (-7890 5250);
FORCEPROP 2 LAST CUSTOM_TXT_CDS <XR_PAGE_TITLE>
J 0
(-7890 5250);
DISPLAY 0.638298 (-7890 5250);
PAINT PINK (-7890 5250);
DISPLAY INVISIBLE (-7890 5250);
FORCEPROP 1 LAST COMMENT_BODY TRUE
J 0
(12 -13);
DISPLAY 0.978723 (12 -13);
PAINT GREEN (12 -13);
DISPLAY INVISIBLE (12 -13);
FORCEPROP 1 LAST Q_DEPT BU9
J 1
(-3763 49);
DISPLAY 1.957447 (-3763 49);
PAINT GREEN (-3763 49);
DISPLAY INVISIBLE (-3763 49);
FORCEPROP 0 LAST CDS_CON_LAST_MODIFIED Thu Aug 24 10:17:15 2023
J 0
(-1885 15);
DISPLAY INVISIBLE (-1885 15);
QUIT
